# S9S_MB_2U (Grand Teton) — schematic netlist excerpt (pin names and nets, part order shuffled) for the footprints in the layout excerpt that follows; sources: Cadence DE-HDL packaged netlist, KiCad conversion of 03242023_DA0F0TMBIJ0_F0T_Motherboard_J_brd_V01_OCP.brd

C910  Q_CAP_DIFFBUS  DIFF BUS_0.22UF 6.3V 20% X6S  pkg C0201  page 173 : \1\ = P5E_CPU0_PE0_TX_C_DN<11> ; \2\ = P5E_CPU0_PE0_TX_DN<11>
R4090  Q_RES  4.7K 1% CHIP  pkg 0402LF  page 172 : A = P3V3_AUX ; B = M2_0_P3V3_ADC_ALERT_R
R4472  Q_RES  0 5% EMPTY  pkg 0402LF  page 196 : A = USB2_PCH_0_R_DN ; B = USB2_0_DN

(kicad_pcb
	(version 20260206)
	(generator "pcbnew")
	(generator_version "10.0")
	(general
		(thickness 1.6)
		(legacy_teardrops no)
	)
	(paper "A4")
	(title_block
		(title "03242023_DA0F0TMBIJ0_F0T_Motherboard_J_brd_V01_OCP.brd")
		(comment 1 "Grand Teton / footprints 2769-2771 of 6105")
	)
	(layers
		(0 "F.Cu" signal "TOP")
		(4 "In1.Cu" signal "GND")
		(6 "In2.Cu" signal "IN1")
		(8 "In3.Cu" signal "GND1")
		(10 "In4.Cu" signal "IN2")
		(12 "In5.Cu" signal "GND2")
		(14 "In6.Cu" signal "IN3")
		(16 "In7.Cu" signal "GND3")
		(18 "In8.Cu" signal "VCC")
		(20 "In9.Cu" signal "VCC1")
		(22 "In10.Cu" signal "GND4")
		(24 "In11.Cu" signal "IN4")
		(26 "In12.Cu" signal "GND5")
		(28 "In13.Cu" signal "IN5")
		(30 "In14.Cu" signal "GND6")
		(32 "In15.Cu" signal "IN6")
		(34 "In16.Cu" signal "GND7")
		(2 "B.Cu" signal "BOTTOM")
		(9 "F.Adhes" user "F.Adhesive")
		(11 "B.Adhes" user "B.Adhesive")
		(13 "F.Paste" user "Package Geometry/Pastemask Top")
		(15 "B.Paste" user "Package Geometry/Pastemask Bottom")
		(5 "F.SilkS" user "Ref Des/Silkscreen Top")
		(7 "B.SilkS" user "Ref Des/Silkscreen Bottom")
		(1 "F.Mask" user "Board Geometry/Soldermask Top")
		(3 "B.Mask" user "Board Geometry/Soldermask Bottom")
		(17 "Dwgs.User" user "User.Drawings")
		(19 "Cmts.User" user "User.Comments")
		(21 "Eco1.User" user "User.Eco1")
		(23 "Eco2.User" user "User.Eco2")
		(25 "Edge.Cuts" user "Board Geometry/Outline")
		(27 "Margin" user)
		(31 "F.CrtYd" user "Package Geometry/Place Bound Top")
		(29 "B.CrtYd" user "Package Geometry/Place Bound Bottom")
		(35 "F.Fab" user "Ref Des/Assembly Top")
		(33 "B.Fab" user "Ref Des/Assembly Bottom")
	)
	(footprint ""
		(layer "F.Cu")
		(at 317.553848 -408.517344 -90)
		(property "Reference" "C910"
			(at 0 0 270)
			(layer "F.SilkS")
			(hide yes)
			(effects
				(font
					(size 1.27 1.27)
				)
			)
		)
		(property "Value" ""
			(at 0 0 270)
			(layer "F.Fab")
			(effects
				(font
					(size 1.27 1.27)
				)
			)
		)
		(duplicate_pad_numbers_are_jumpers no)
		(fp_line
			(start -0.299974 0.150114)
			(end -0.299974 -0.150114)
			(stroke
				(width 0.1)
				(type default)
			)
			(layer "F.Fab")
		)
		(fp_line
			(start 0.299974 0.150114)
			(end -0.299974 0.150114)
			(stroke
				(width 0.1)
				(type default)
			)
			(layer "F.Fab")
		)
		(fp_line
			(start -0.299974 -0.150114)
			(end 0.299974 -0.150114)
			(stroke
				(width 0.1)
				(type default)
			)
			(layer "F.Fab")
		)
		(fp_line
			(start 0.299974 -0.150114)
			(end 0.299974 0.150114)
			(stroke
				(width 0.1)
				(type default)
			)
			(layer "F.Fab")
		)
		(pad "1" smd rect
			(at -0.2667 0 270)
			(size 0.3048 0.381)
			(layers "F.Cu" "F.Mask" "F.Paste")
			(net "P5E_CPU0_PE0_TX_C_DN<11>")
		)
		(pad "2" smd rect
			(at 0.2667 0 270)
			(size 0.3048 0.381)
			(layers "F.Cu" "F.Mask" "F.Paste")
			(net "P5E_CPU0_PE0_TX_DN<11>")
		)
	)
	(footprint ""
		(layer "F.Cu")
		(at 160.28035 -43.832526 90)
		(property "Reference" "R4472"
			(at 0 0 90)
			(layer "F.SilkS")
			(hide yes)
			(effects
				(font
					(size 1.27 1.27)
				)
			)
		)
		(property "Value" ""
			(at 0 0 90)
			(layer "F.Fab")
			(effects
				(font
					(size 1.27 1.27)
				)
			)
		)
		(duplicate_pad_numbers_are_jumpers no)
		(fp_line
			(start 0.7874 -0.4064)
			(end 0.7874 0.4064)
			(stroke
				(width 0.1524)
				(type default)
			)
			(layer "F.SilkS")
		)
		(fp_line
			(start 0.7874 0.4064)
			(end -0.7874 0.4064)
			(stroke
				(width 0.1524)
				(type default)
			)
			(layer "F.SilkS")
		)
		(fp_line
			(start -0.12065 -0.305054)
			(end -0.12065 -0.2794)
			(stroke
				(width 0.1)
				(type default)
			)
			(layer "F.Fab")
		)
		(fp_line
			(start -0.67945 -0.305054)
			(end -0.12065 -0.305054)
			(stroke
				(width 0.1)
				(type default)
			)
			(layer "F.Fab")
		)
		(fp_line
			(start 0.67945 -0.3048)
			(end 0.67945 0.3048)
			(stroke
				(width 0.1)
				(type default)
			)
			(layer "F.Fab")
		)
		(fp_line
			(start 0.12065 -0.3048)
			(end 0.67945 -0.3048)
			(stroke
				(width 0.1)
				(type default)
			)
			(layer "F.Fab")
		)
		(fp_line
			(start 0.12065 -0.2794)
			(end 0.12065 -0.3048)
			(stroke
				(width 0.1)
				(type default)
			)
			(layer "F.Fab")
		)
		(fp_line
			(start -0.12065 -0.2794)
			(end 0.12065 -0.2794)
			(stroke
				(width 0.1)
				(type default)
			)
			(layer "F.Fab")
		)
		(fp_line
			(start 0.120396 0.2794)
			(end -0.12065 0.2794)
			(stroke
				(width 0.1)
				(type default)
			)
			(layer "F.Fab")
		)
		(fp_line
			(start -0.12065 0.2794)
			(end -0.12065 0.3048)
			(stroke
				(width 0.1)
				(type default)
			)
			(layer "F.Fab")
		)
		(fp_line
			(start 0.67945 0.3048)
			(end 0.120396 0.3048)
			(stroke
				(width 0.1)
				(type default)
			)
			(layer "F.Fab")
		)
		(fp_line
			(start 0.120396 0.3048)
			(end 0.120396 0.2794)
			(stroke
				(width 0.1)
				(type default)
			)
			(layer "F.Fab")
		)
		(fp_line
			(start -0.12065 0.3048)
			(end -0.67945 0.3048)
			(stroke
				(width 0.1)
				(type default)
			)
			(layer "F.Fab")
		)
		(fp_line
			(start -0.67945 0.3048)
			(end -0.67945 -0.305054)
			(stroke
				(width 0.1)
				(type default)
			)
			(layer "F.Fab")
		)
		(pad "1" smd rect
			(at -0.40005 0 270)
			(size 0.4572 0.508)
			(layers "F.Cu" "F.Mask" "F.Paste")
			(net "USB2_PCH_0_R_DN")
		)
		(pad "2" smd rect
			(at 0.40005 0 270)
			(size 0.4572 0.508)
			(layers "F.Cu" "F.Mask" "F.Paste")
			(net "USB2_0_DN")
		)
	)
	(footprint ""
		(layer "F.Cu")
		(at 148.1963 -48.283368)
		(property "Reference" "R4090"
			(at 0 0 0)
			(layer "F.SilkS")
			(hide yes)
			(effects
				(font
					(size 1.27 1.27)
				)
			)
		)
		(property "Value" ""
			(at 0 0 0)
			(layer "F.Fab")
			(effects
				(font
					(size 1.27 1.27)
				)
			)
		)
		(duplicate_pad_numbers_are_jumpers no)
		(fp_line
			(start -0.7874 -0.4064)
			(end 0.7874 -0.4064)
			(stroke
				(width 0.1524)
				(type default)
			)
			(layer "F.SilkS")
		)
		(fp_line
			(start -0.7874 0.4064)
			(end -0.7874 -0.4064)
			(stroke
				(width 0.1524)
				(type default)
			)
			(layer "F.SilkS")
		)
		(fp_line
			(start 0.7874 -0.4064)
			(end 0.7874 0.4064)
			(stroke
				(width 0.1524)
				(type default)
			)
			(layer "F.SilkS")
		)
		(fp_line
			(start 0.7874 0.4064)
			(end -0.7874 0.4064)
			(stroke
				(width 0.1524)
				(type default)
			)
			(layer "F.SilkS")
		)
		(fp_line
			(start -0.67945 -0.305054)
			(end -0.12065 -0.305054)
			(stroke
				(width 0.1)
				(type default)
			)
			(layer "F.Fab")
		)
		(fp_line
			(start -0.67945 0.3048)
			(end -0.67945 -0.305054)
			(stroke
				(width 0.1)
				(type default)
			)
			(layer "F.Fab")
		)
		(fp_line
			(start -0.12065 -0.305054)
			(end -0.12065 -0.2794)
			(stroke
				(width 0.1)
				(type default)
			)
			(layer "F.Fab")
		)
		(fp_line
			(start -0.12065 -0.2794)
			(end 0.12065 -0.2794)
			(stroke
				(width 0.1)
				(type default)
			)
			(layer "F.Fab")
		)
		(fp_line
			(start -0.12065 0.2794)
			(end -0.12065 0.3048)
			(stroke
				(width 0.1)
				(type default)
			)
			(layer "F.Fab")
		)
		(fp_line
			(start -0.12065 0.3048)
			(end -0.67945 0.3048)
			(stroke
				(width 0.1)
				(type default)
			)
			(layer "F.Fab")
		)
		(fp_line
			(start 0.120396 0.2794)
			(end -0.12065 0.2794)
			(stroke
				(width 0.1)
				(type default)
			)
			(layer "F.Fab")
		)
		(fp_line
			(start 0.120396 0.3048)
			(end 0.120396 0.2794)
			(stroke
				(width 0.1)
				(type default)
			)
			(layer "F.Fab")
		)
		(fp_line
			(start 0.12065 -0.3048)
			(end 0.67945 -0.3048)
			(stroke
				(width 0.1)
				(type default)
			)
			(layer "F.Fab")
		)
		(fp_line
			(start 0.12065 -0.2794)
			(end 0.12065 -0.3048)
			(stroke
				(width 0.1)
				(type default)
			)
			(layer "F.Fab")
		)
		(fp_line
			(start 0.67945 -0.3048)
			(end 0.67945 0.3048)
			(stroke
				(width 0.1)
				(type default)
			)
			(layer "F.Fab")
		)
		(fp_line
			(start 0.67945 0.3048)
			(end 0.120396 0.3048)
			(stroke
				(width 0.1)
				(type default)
			)
			(layer "F.Fab")
		)
		(pad "1" smd circle
			(at -0.40005 0)
			(size 0 0)
			(layers "F.Cu" "F.Mask" "F.Paste")
			(net "P3V3_AUX")
		)
		(pad "2" smd circle
			(at 0.40005 0)
			(size 0 0)
			(layers "F.Cu" "F.Mask" "F.Paste")
			(net "M2_0_P3V3_ADC_ALERT_R")
		)
	)
)
